# S9S_MB_2U (Grand Teton) — schematic netlist excerpt (pin names and nets, part order shuffled) for the footprints in the layout excerpt that follows; sources: Cadence DE-HDL packaged netlist, KiCad conversion of 03242023_DA0F0TMBIJ0_F0T_Motherboard_J_brd_V01_OCP.brd

C2387  Q_CAP  100NF 50V 10% EMPTY  pkg C0402  page 307 : A = P12V_AUX ; B = GND
R308  Q_RES  0 5% CHIP  pkg 0402LF  page 284 : A = PWRGD_PVCCIN_CPU1 ; B = PWRGD_PVCCIN_CPU1_R

(kicad_pcb
	(version 20260206)
	(generator "pcbnew")
	(generator_version "10.0")
	(general
		(thickness 1.6)
		(legacy_teardrops no)
	)
	(paper "A4")
	(title_block
		(title "03242023_DA0F0TMBIJ0_F0T_Motherboard_J_brd_V01_OCP.brd")
		(comment 1 "Grand Teton / footprints 3650-3651 of 6105")
	)
	(layers
		(0 "F.Cu" signal "TOP")
		(4 "In1.Cu" signal "GND")
		(6 "In2.Cu" signal "IN1")
		(8 "In3.Cu" signal "GND1")
		(10 "In4.Cu" signal "IN2")
		(12 "In5.Cu" signal "GND2")
		(14 "In6.Cu" signal "IN3")
		(16 "In7.Cu" signal "GND3")
		(18 "In8.Cu" signal "VCC")
		(20 "In9.Cu" signal "VCC1")
		(22 "In10.Cu" signal "GND4")
		(24 "In11.Cu" signal "IN4")
		(26 "In12.Cu" signal "GND5")
		(28 "In13.Cu" signal "IN5")
		(30 "In14.Cu" signal "GND6")
		(32 "In15.Cu" signal "IN6")
		(34 "In16.Cu" signal "GND7")
		(2 "B.Cu" signal "BOTTOM")
		(9 "F.Adhes" user "F.Adhesive")
		(11 "B.Adhes" user "B.Adhesive")
		(13 "F.Paste" user "Package Geometry/Pastemask Top")
		(15 "B.Paste" user "Package Geometry/Pastemask Bottom")
		(5 "F.SilkS" user "Ref Des/Silkscreen Top")
		(7 "B.SilkS" user "Ref Des/Silkscreen Bottom")
		(1 "F.Mask" user "Board Geometry/Soldermask Top")
		(3 "B.Mask" user "Board Geometry/Soldermask Bottom")
		(17 "Dwgs.User" user "User.Drawings")
		(19 "Cmts.User" user "User.Comments")
		(21 "Eco1.User" user "User.Eco1")
		(23 "Eco2.User" user "User.Eco2")
		(25 "Edge.Cuts" user "Board Geometry/Outline")
		(27 "Margin" user)
		(31 "F.CrtYd" user "Package Geometry/Place Bound Top")
		(29 "B.CrtYd" user "Package Geometry/Place Bound Bottom")
		(35 "F.Fab" user "Ref Des/Assembly Top")
		(33 "B.Fab" user "Ref Des/Assembly Bottom")
	)
	(footprint ""
		(layer "F.Cu")
		(at 307.6956 -28.7528 180)
		(property "Reference" "C2387"
			(at 0 0 180)
			(layer "F.SilkS")
			(hide yes)
			(effects
				(font
					(size 1.27 1.27)
				)
			)
		)
		(property "Value" ""
			(at 0 0 180)
			(layer "F.Fab")
			(effects
				(font
					(size 1.27 1.27)
				)
			)
		)
		(duplicate_pad_numbers_are_jumpers no)
		(fp_line
			(start 0.7874 0.4064)
			(end -0.7874 0.4064)
			(stroke
				(width 0.1524)
				(type default)
			)
			(layer "F.SilkS")
		)
		(fp_line
			(start 0.7874 -0.4064)
			(end 0.7874 0.4064)
			(stroke
				(width 0.1524)
				(type default)
			)
			(layer "F.SilkS")
		)
		(fp_line
			(start -0.7874 0.4064)
			(end -0.7874 -0.4064)
			(stroke
				(width 0.1524)
				(type default)
			)
			(layer "F.SilkS")
		)
		(fp_line
			(start -0.7874 -0.4064)
			(end 0.7874 -0.4064)
			(stroke
				(width 0.1524)
				(type default)
			)
			(layer "F.SilkS")
		)
		(fp_line
			(start 0.67945 0.3048)
			(end 0.120396 0.3048)
			(stroke
				(width 0.1)
				(type default)
			)
			(layer "F.Fab")
		)
		(fp_line
			(start 0.67945 -0.3048)
			(end 0.67945 0.3048)
			(stroke
				(width 0.1)
				(type default)
			)
			(layer "F.Fab")
		)
		(fp_line
			(start 0.12065 -0.2794)
			(end 0.12065 -0.3048)
			(stroke
				(width 0.1)
				(type default)
			)
			(layer "F.Fab")
		)
		(fp_line
			(start 0.12065 -0.3048)
			(end 0.67945 -0.3048)
			(stroke
				(width 0.1)
				(type default)
			)
			(layer "F.Fab")
		)
		(fp_line
			(start 0.120396 0.3048)
			(end 0.120396 0.2794)
			(stroke
				(width 0.1)
				(type default)
			)
			(layer "F.Fab")
		)
		(fp_line
			(start 0.120396 0.2794)
			(end -0.12065 0.2794)
			(stroke
				(width 0.1)
				(type default)
			)
			(layer "F.Fab")
		)
		(fp_line
			(start -0.12065 0.3048)
			(end -0.67945 0.3048)
			(stroke
				(width 0.1)
				(type default)
			)
			(layer "F.Fab")
		)
		(fp_line
			(start -0.12065 0.2794)
			(end -0.12065 0.3048)
			(stroke
				(width 0.1)
				(type default)
			)
			(layer "F.Fab")
		)
		(fp_line
			(start -0.12065 -0.2794)
			(end 0.12065 -0.2794)
			(stroke
				(width 0.1)
				(type default)
			)
			(layer "F.Fab")
		)
		(fp_line
			(start -0.12065 -0.305054)
			(end -0.12065 -0.2794)
			(stroke
				(width 0.1)
				(type default)
			)
			(layer "F.Fab")
		)
		(fp_line
			(start -0.67945 0.3048)
			(end -0.67945 -0.305054)
			(stroke
				(width 0.1)
				(type default)
			)
			(layer "F.Fab")
		)
		(fp_line
			(start -0.67945 -0.305054)
			(end -0.12065 -0.305054)
			(stroke
				(width 0.1)
				(type default)
			)
			(layer "F.Fab")
		)
		(pad "1" smd circle
			(at -0.40005 0 180)
			(size 0 0)
			(layers "F.Cu" "F.Mask" "F.Paste")
			(net "P12V_AUX")
		)
		(pad "2" smd circle
			(at 0.40005 0 180)
			(size 0 0)
			(layers "F.Cu" "F.Mask" "F.Paste")
			(net "GND")
		)
	)
	(footprint ""
		(layer "F.Cu")
		(at 101.380036 -360.929174 -90)
		(property "Reference" "R308"
			(at 0 0 270)
			(layer "F.SilkS")
			(hide yes)
			(effects
				(font
					(size 1.27 1.27)
				)
			)
		)
		(property "Value" ""
			(at 0 0 270)
			(layer "F.Fab")
			(effects
				(font
					(size 1.27 1.27)
				)
			)
		)
		(duplicate_pad_numbers_are_jumpers no)
		(fp_line
			(start -0.7874 0.4064)
			(end -0.7874 -0.4064)
			(stroke
				(width 0.1524)
				(type default)
			)
			(layer "F.SilkS")
		)
		(fp_line
			(start 0.7874 0.4064)
			(end -0.7874 0.4064)
			(stroke
				(width 0.1524)
				(type default)
			)
			(layer "F.SilkS")
		)
		(fp_line
			(start -0.7874 -0.4064)
			(end 0.7874 -0.4064)
			(stroke
				(width 0.1524)
				(type default)
			)
			(layer "F.SilkS")
		)
		(fp_line
			(start 0.7874 -0.4064)
			(end 0.7874 0.4064)
			(stroke
				(width 0.1524)
				(type default)
			)
			(layer "F.SilkS")
		)
		(fp_line
			(start -0.67945 0.3048)
			(end -0.67945 -0.305054)
			(stroke
				(width 0.1)
				(type default)
			)
			(layer "F.Fab")
		)
		(fp_line
			(start -0.12065 0.3048)
			(end -0.67945 0.3048)
			(stroke
				(width 0.1)
				(type default)
			)
			(layer "F.Fab")
		)
		(fp_line
			(start 0.120396 0.3048)
			(end 0.120396 0.2794)
			(stroke
				(width 0.1)
				(type default)
			)
			(layer "F.Fab")
		)
		(fp_line
			(start 0.67945 0.3048)
			(end 0.120396 0.3048)
			(stroke
				(width 0.1)
				(type default)
			)
			(layer "F.Fab")
		)
		(fp_line
			(start -0.12065 0.2794)
			(end -0.12065 0.3048)
			(stroke
				(width 0.1)
				(type default)
			)
			(layer "F.Fab")
		)
		(fp_line
			(start 0.120396 0.2794)
			(end -0.12065 0.2794)
			(stroke
				(width 0.1)
				(type default)
			)
			(layer "F.Fab")
		)
		(fp_line
			(start -0.12065 -0.2794)
			(end 0.12065 -0.2794)
			(stroke
				(width 0.1)
				(type default)
			)
			(layer "F.Fab")
		)
		(fp_line
			(start 0.12065 -0.2794)
			(end 0.12065 -0.3048)
			(stroke
				(width 0.1)
				(type default)
			)
			(layer "F.Fab")
		)
		(fp_line
			(start 0.12065 -0.3048)
			(end 0.67945 -0.3048)
			(stroke
				(width 0.1)
				(type default)
			)
			(layer "F.Fab")
		)
		(fp_line
			(start 0.67945 -0.3048)
			(end 0.67945 0.3048)
			(stroke
				(width 0.1)
				(type default)
			)
			(layer "F.Fab")
		)
		(fp_line
			(start -0.67945 -0.305054)
			(end -0.12065 -0.305054)
			(stroke
				(width 0.1)
				(type default)
			)
			(layer "F.Fab")
		)
		(fp_line
			(start -0.12065 -0.305054)
			(end -0.12065 -0.2794)
			(stroke
				(width 0.1)
				(type default)
			)
			(layer "F.Fab")
		)
		(pad "1" smd circle
			(at -0.40005 0 270)
			(size 0 0)
			(layers "F.Cu" "F.Mask" "F.Paste")
			(net "PWRGD_PVCCIN_CPU1")
		)
		(pad "2" smd circle
			(at 0.40005 0 270)
			(size 0 0)
			(layers "F.Cu" "F.Mask" "F.Paste")
			(net "PWRGD_PVCCIN_CPU1_R")
		)
	)
)
